(kicad_pcb
	(version 20260206)
	(generator "pcbnew")
	(generator_version "10.0")
	(general
		(thickness 1.6)
		(legacy_teardrops no)
	)
	(paper "A4")
	(title_block
		(title "Bryce Canyon_F.DPB_16315-1-OCP.brd")
		(comment 1 "Bryce Canyon / footprints 159-165 of 2223")
	)
	(layers
		(0 "F.Cu" signal "TOP")
		(4 "In1.Cu" signal "L2GND")
		(6 "In2.Cu" signal "L3")
		(8 "In3.Cu" signal "L4GND")
		(10 "In4.Cu" signal "L5")
		(12 "In5.Cu" signal "L6VCC")
		(14 "In6.Cu" signal "L7VCC")
		(16 "In7.Cu" signal "L8")
		(18 "In8.Cu" signal "L9GND")
		(20 "In9.Cu" signal "L10")
		(22 "In10.Cu" signal "L11GND")
		(2 "B.Cu" signal "BOTTOM")
		(9 "F.Adhes" user "F.Adhesive")
		(11 "B.Adhes" user "B.Adhesive")
		(13 "F.Paste" user "Package Geometry/Pastemask Top")
		(15 "B.Paste" user "Package Geometry/Pastemask Bottom")
		(5 "F.SilkS" user "Ref Des/Silkscreen Top")
		(7 "B.SilkS" user "Ref Des/Silkscreen Bottom")
		(1 "F.Mask" user "Board Geometry/Soldermask Top")
		(3 "B.Mask" user "Board Geometry/Soldermask Bottom")
		(17 "Dwgs.User" user "User.Drawings")
		(19 "Cmts.User" user "User.Comments")
		(21 "Eco1.User" user "User.Eco1")
		(23 "Eco2.User" user "User.Eco2")
		(25 "Edge.Cuts" user "Board Geometry/Outline")
		(27 "Margin" user)
		(31 "F.CrtYd" user "Package Geometry/Place Bound Top")
		(29 "B.CrtYd" user "Package Geometry/Place Bound Bottom")
		(35 "F.Fab" user "Ref Des/Assembly Top")
		(33 "B.Fab" user "Ref Des/Assembly Bottom")
	)
	(footprint ""
		(layer "F.Cu")
		(at 329.819 -189.335918 180)
		(property "Reference" "C281"
			(at 0 0 180)
			(layer "F.SilkS")
			(hide yes)
			(effects
				(font
					(size 1.27 1.27)
				)
			)
		)
		(property "Value" "SC1U25V3KX-GP"
			(at 0 -2.8194 180)
			(unlocked yes)
			(layer "F.Fab")
			(hide yes)
			(effects
				(font
					(size 1.016 1.016)
					(thickness 0.1524)
				)
			)
		)
		(property "Device Type" "C603H36"
			(at 0 -4.3434 180)
			(unlocked yes)
			(layer "F.Fab")
			(hide yes)
			(effects
				(font
					(size 1.016 1.016)
					(thickness 0.1524)
				)
			)
		)
		(duplicate_pad_numbers_are_jumpers no)
		(fp_line
			(start 0.508 0)
			(end -0.508 0)
			(stroke
				(width 0.2032)
				(type default)
			)
			(layer "F.SilkS")
		)
		(fp_rect
			(start -0.5842 1.3335)
			(end 0.5842 -1.3335)
			(stroke
				(width 0)
				(type default)
			)
			(fill no)
			(layer "F.CrtYd")
		)
		(fp_rect
			(start -0.5842 1.3335)
			(end 0.5842 -1.3335)
			(stroke
				(width 0)
				(type default)
			)
			(fill no)
			(layer "F.Fab")
		)
		(pad "1" smd custom
			(at 0 -0.762 180)
			(size 0.2159 0.2159)
			(layers "F.Cu" "F.Mask" "F.Paste")
			(net "P12V_HDD18")
			(options
				(clearance outline)
				(anchor circle)
			)
			(primitives
				(gr_poly
					(pts
						(arc
							(start -0.3302 -0.4318)
							(mid -0.402042 -0.402042)
							(end -0.4318 -0.3302)
						)
						(arc
							(start -0.4318 0.3302)
							(mid -0.402042 0.402042)
							(end -0.3302 0.4318)
						)
						(arc
							(start 0.3302 0.4318)
							(mid 0.402042 0.402042)
							(end 0.4318 0.3302)
						)
						(arc
							(start 0.4318 -0.3302)
							(mid 0.402042 -0.402042)
							(end 0.3302 -0.4318)
						)
					)
					(width 0)
					(fill yes)
				)
			)
		)
		(pad "2" smd custom
			(at 0 0.762 180)
			(size 0.2159 0.2159)
			(layers "F.Cu" "F.Mask" "F.Paste")
			(net "GND")
			(options
				(clearance outline)
				(anchor circle)
			)
			(primitives
				(gr_poly
					(pts
						(arc
							(start -0.3302 -0.4318)
							(mid -0.402042 -0.402042)
							(end -0.4318 -0.3302)
						)
						(arc
							(start -0.4318 0.3302)
							(mid -0.402042 0.402042)
							(end -0.3302 0.4318)
						)
						(arc
							(start 0.3302 0.4318)
							(mid 0.402042 0.402042)
							(end 0.4318 0.3302)
						)
						(arc
							(start 0.4318 -0.3302)
							(mid 0.402042 -0.402042)
							(end 0.3302 -0.4318)
						)
					)
					(width 0)
					(fill yes)
				)
			)
		)
	)
	(footprint ""
		(layer "F.Cu")
		(at 272.542 -355.905054 180)
		(property "Reference" "VIA37"
			(at 0 0 180)
			(layer "F.SilkS")
			(hide yes)
			(effects
				(font
					(size 1.27 1.27)
				)
			)
		)
		(property "Value" "100OHM-8L-1D6MM-L18L16-GP"
			(at -3.7211 -4.5085 180)
			(unlocked yes)
			(layer "F.Fab")
			(hide yes)
			(effects
				(font
					(size 1.016 1.016)
					(thickness 0.1524)
				)
			)
		)
		(property "Device Type" "VIA-PCIE-4P-394076"
			(at -3.7211 -6.0325 180)
			(unlocked yes)
			(layer "F.Fab")
			(hide yes)
			(effects
				(font
					(size 1.016 1.016)
					(thickness 0.1524)
				)
			)
		)
		(duplicate_pad_numbers_are_jumpers no)
		(fp_rect
			(start -1.9685 0.381)
			(end 1.9685 -0.381)
			(stroke
				(width 0)
				(type default)
			)
			(fill no)
			(layer "F.CrtYd")
		)
		(fp_rect
			(start -1.9685 0.381)
			(end 1.9685 -0.381)
			(stroke
				(width 0)
				(type default)
			)
			(fill no)
			(layer "F.Fab")
		)
		(pad "1" thru_hole circle
			(at -1.5875 0 180)
			(size 0.508 0.508)
			(drill 0.254)
			(layers "*.Cu" "*.Mask")
			(remove_unused_layers no)
			(net "GND")
			(clearance 0.127)
			(thermal_gap 0.127)
		)
		(pad "2" thru_hole circle
			(at -0.5715 0 180)
			(size 0.508 0.508)
			(drill 0.254)
			(layers "*.Cu" "*.Mask")
			(remove_unused_layers no)
			(net "PHY_SCC_A_TO_DRV_A_2_DP")
			(clearance 0.127)
			(thermal_gap 0.127)
		)
		(pad "3" thru_hole circle
			(at 0.5715 0 180)
			(size 0.508 0.508)
			(drill 0.254)
			(layers "*.Cu" "*.Mask")
			(remove_unused_layers no)
			(net "PHY_SCC_A_TO_DRV_A_2_DN")
			(clearance 0.127)
			(thermal_gap 0.127)
		)
		(pad "4" thru_hole circle
			(at 1.5875 0 180)
			(size 0.508 0.508)
			(drill 0.254)
			(layers "*.Cu" "*.Mask")
			(remove_unused_layers no)
			(net "GND")
			(clearance 0.127)
			(thermal_gap 0.127)
		)
	)
	(footprint ""
		(layer "F.Cu")
		(at 17.800066 -94.400116)
		(property "Reference" "FLED13"
			(at 0 0 0)
			(layer "F.SilkS")
			(hide yes)
			(effects
				(font
					(size 1.27 1.27)
				)
			)
		)
		(property "Value" "LED-BY-19-GP"
			(at -2.132076 1.414018 0)
			(unlocked yes)
			(layer "F.Fab")
			(hide yes)
			(effects
				(font
					(size 1.016 1.016)
					(thickness 0.1524)
				)
			)
		)
		(property "Device Type" "LED-1615-4PH26"
			(at -2.132076 -0.109982 0)
			(unlocked yes)
			(layer "F.Fab")
			(hide yes)
			(effects
				(font
					(size 1.016 1.016)
					(thickness 0.1524)
				)
			)
		)
		(duplicate_pad_numbers_are_jumpers no)
		(fp_line
			(start -1.2954 0.254)
			(end -1.2954 1.6002)
			(stroke
				(width 0.508)
				(type default)
			)
			(layer "F.SilkS")
		)
		(fp_line
			(start -1.2954 1.6002)
			(end 1.2954 1.6002)
			(stroke
				(width 0.508)
				(type default)
			)
			(layer "F.SilkS")
		)
		(fp_line
			(start -1.1176 -1.4224)
			(end 1.1176 -1.4224)
			(stroke
				(width 0.1524)
				(type default)
			)
			(layer "F.SilkS")
		)
		(fp_line
			(start -1.1176 1.4224)
			(end -1.1176 -1.4224)
			(stroke
				(width 0.1524)
				(type default)
			)
			(layer "F.SilkS")
		)
		(fp_line
			(start 1.1176 -1.4224)
			(end 1.1176 1.4224)
			(stroke
				(width 0.1524)
				(type default)
			)
			(layer "F.SilkS")
		)
		(fp_line
			(start 1.1176 1.4224)
			(end -1.1176 1.4224)
			(stroke
				(width 0.1524)
				(type default)
			)
			(layer "F.SilkS")
		)
		(fp_line
			(start 1.2954 1.6002)
			(end 1.2954 0.254)
			(stroke
				(width 0.508)
				(type default)
			)
			(layer "F.SilkS")
		)
		(fp_rect
			(start -0.7493 0.8001)
			(end 0.7493 -0.8001)
			(stroke
				(width 0)
				(type default)
			)
			(fill no)
			(layer "F.CrtYd")
		)
		(fp_poly
			(pts
				(xy -1.3716 1.6764) (xy -1.3716 -1.6764) (xy 1.3716 -1.6764) (xy 1.3716 0.0635) (xy 0.7493 0.0635)
				(xy 0.7493 -0.8001) (xy -0.7493 -0.8001) (xy -0.7493 0.8001) (xy 0.7493 0.8001) (xy 0.7493 0.0762)
				(xy 1.3716 0.0762) (xy 1.3716 1.6764)
			)
			(stroke
				(width 0)
				(type default)
			)
			(fill no)
			(layer "F.CrtYd")
		)
		(fp_rect
			(start -1.3716 1.6764)
			(end 1.3716 -1.6764)
			(stroke
				(width 0)
				(type default)
			)
			(fill no)
			(layer "F.Fab")
		)
		(pad "1" smd rect
			(at 0.50038 -0.73025)
			(size 0.7112 0.8636)
			(layers "F.Cu" "F.Mask" "F.Paste")
			(net "DRV_ACT_12")
		)
		(pad "2" smd rect
			(at -0.50038 -0.73025)
			(size 0.7112 0.8636)
			(layers "F.Cu" "F.Mask" "F.Paste")
			(net "FLT_HDD12")
		)
		(pad "3" smd rect
			(at 0.50038 0.73025)
			(size 0.7112 0.8636)
			(layers "F.Cu" "F.Mask" "F.Paste")
			(net "DRV_ACT_12_N")
		)
		(pad "4" smd rect
			(at -0.50038 0.73025)
			(size 0.7112 0.8636)
			(layers "F.Cu" "F.Mask" "F.Paste")
			(net "FLT_HDD12_N")
		)
	)
	(footprint ""
		(layer "F.Cu")
		(at 226.7458 -390.377172)
		(property "Reference" "R1293"
			(at 0 0 0)
			(layer "F.SilkS")
			(hide yes)
			(effects
				(font
					(size 1.27 1.27)
				)
			)
		)
		(property "Value" "3K3R3F-GP"
			(at -0.0254 -2.5146 0)
			(unlocked yes)
			(layer "F.Fab")
			(hide yes)
			(effects
				(font
					(size 1.016 1.016)
					(thickness 0.1524)
				)
			)
		)
		(property "Device Type" "R603H22"
			(at -0.0254 -4.0386 0)
			(unlocked yes)
			(layer "F.Fab")
			(hide yes)
			(effects
				(font
					(size 1.016 1.016)
					(thickness 0.1524)
				)
			)
		)
		(duplicate_pad_numbers_are_jumpers no)
		(fp_line
			(start -0.4826 0)
			(end -0.2032 0)
			(stroke
				(width 0.2032)
				(type default)
			)
			(layer "F.SilkS")
		)
		(fp_line
			(start 0.2032 0)
			(end 0.4826 0)
			(stroke
				(width 0.2032)
				(type default)
			)
			(layer "F.SilkS")
		)
		(fp_rect
			(start -0.5842 1.3335)
			(end 0.5842 -1.3335)
			(stroke
				(width 0)
				(type default)
			)
			(fill no)
			(layer "F.CrtYd")
		)
		(fp_rect
			(start -0.5842 1.3335)
			(end 0.5842 -1.3335)
			(stroke
				(width 0)
				(type default)
			)
			(fill no)
			(layer "F.Fab")
		)
		(pad "1" smd custom
			(at 0 -0.762)
			(size 0.2159 0.2159)
			(layers "F.Cu" "F.Mask" "F.Paste")
			(net "P12V_IN")
			(options
				(clearance outline)
				(anchor circle)
			)
			(primitives
				(gr_poly
					(pts
						(arc
							(start -0.3302 -0.4318)
							(mid -0.402042 -0.402042)
							(end -0.4318 -0.3302)
						)
						(arc
							(start -0.4318 0.3302)
							(mid -0.402042 0.402042)
							(end -0.3302 0.4318)
						)
						(arc
							(start 0.3302 0.4318)
							(mid 0.402042 0.402042)
							(end 0.4318 0.3302)
						)
						(arc
							(start 0.4318 -0.3302)
							(mid 0.402042 -0.402042)
							(end 0.3302 -0.4318)
						)
					)
					(width 0)
					(fill yes)
				)
			)
		)
		(pad "2" smd custom
			(at 0 0.762)
			(size 0.2159 0.2159)
			(layers "F.Cu" "F.Mask" "F.Paste")
			(net "VCCP_IN")
			(options
				(clearance outline)
				(anchor circle)
			)
			(primitives
				(gr_poly
					(pts
						(arc
							(start -0.3302 -0.4318)
							(mid -0.402042 -0.402042)
							(end -0.4318 -0.3302)
						)
						(arc
							(start -0.4318 0.3302)
							(mid -0.402042 0.402042)
							(end -0.3302 0.4318)
						)
						(arc
							(start 0.3302 0.4318)
							(mid 0.402042 0.402042)
							(end 0.4318 0.3302)
						)
						(arc
							(start 0.4318 -0.3302)
							(mid 0.402042 -0.402042)
							(end 0.3302 -0.4318)
						)
					)
					(width 0)
					(fill yes)
				)
			)
		)
	)
	(footprint ""
		(layer "F.Cu")
		(at 111.499396 -168.126918 -90)
		(property "Reference" "C243"
			(at 0 0 270)
			(layer "F.SilkS")
			(hide yes)
			(effects
				(font
					(size 1.27 1.27)
				)
			)
		)
		(property "Value" "SCD033U25V2KX-GP"
			(at 1.1811 -2.7051 270)
			(unlocked yes)
			(layer "F.Fab")
			(hide yes)
			(effects
				(font
					(size 1.016 1.016)
					(thickness 0.1524)
				)
			)
		)
		(property "Device Type" "C402H22"
			(at 1.1811 -4.2291 270)
			(unlocked yes)
			(layer "F.Fab")
			(hide yes)
			(effects
				(font
					(size 1.016 1.016)
					(thickness 0.1524)
				)
			)
		)
		(duplicate_pad_numbers_are_jumpers no)
		(fp_rect
			(start -0.4318 0.9525)
			(end 0.4318 -0.9525)
			(stroke
				(width 0)
				(type default)
			)
			(fill no)
			(layer "F.CrtYd")
		)
		(fp_rect
			(start -0.4318 0.9525)
			(end 0.4318 -0.9525)
			(stroke
				(width 0)
				(type default)
			)
			(fill no)
			(layer "F.Fab")
		)
		(pad "1" smd custom
			(at 0 -0.4445 270)
			(size 0.1524 0.1524)
			(layers "F.Cu" "F.Mask" "F.Paste")
			(net "SW_HDD_P15")
			(options
				(clearance outline)
				(anchor circle)
			)
			(primitives
				(gr_poly
					(pts
						(arc
							(start 0.3048 -0.2032)
							(mid 0.275042 -0.275042)
							(end 0.2032 -0.3048)
						)
						(arc
							(start -0.2032 -0.3048)
							(mid -0.275042 -0.275042)
							(end -0.3048 -0.2032)
						)
						(arc
							(start -0.3048 0.2032)
							(mid -0.275042 0.275042)
							(end -0.2032 0.3048)
						)
						(arc
							(start 0.2032 0.3048)
							(mid 0.275042 0.275042)
							(end 0.3048 0.2032)
						)
					)
					(width 0)
					(fill yes)
				)
			)
		)
		(pad "2" smd custom
			(at 0 0.4445 270)
			(size 0.1524 0.1524)
			(layers "F.Cu" "F.Mask" "F.Paste")
			(net "GND")
			(options
				(clearance outline)
				(anchor circle)
			)
			(primitives
				(gr_poly
					(pts
						(arc
							(start 0.3048 -0.2032)
							(mid 0.275042 -0.275042)
							(end 0.2032 -0.3048)
						)
						(arc
							(start -0.2032 -0.3048)
							(mid -0.275042 -0.275042)
							(end -0.3048 -0.2032)
						)
						(arc
							(start -0.3048 0.2032)
							(mid -0.275042 0.275042)
							(end -0.2032 0.3048)
						)
						(arc
							(start 0.2032 0.3048)
							(mid 0.275042 0.275042)
							(end 0.3048 0.2032)
						)
					)
					(width 0)
					(fill yes)
				)
			)
		)
	)
	(footprint ""
		(layer "F.Cu")
		(at 283.2608 -272.3134 180)
		(property "Reference" "R120"
			(at 0 0 180)
			(layer "F.SilkS")
			(hide yes)
			(effects
				(font
					(size 1.27 1.27)
				)
			)
		)
		(property "Value" "4K7R2F-GP"
			(at 0.064008 -3.993896 180)
			(unlocked yes)
			(layer "F.Fab")
			(hide yes)
			(effects
				(font
					(size 1.016 1.016)
					(thickness 0.1524)
				)
			)
		)
		(property "Device Type" "R402H16"
			(at 0.064008 -5.517896 180)
			(unlocked yes)
			(layer "F.Fab")
			(hide yes)
			(effects
				(font
					(size 1.016 1.016)
					(thickness 0.1524)
				)
			)
		)
		(duplicate_pad_numbers_are_jumpers no)
		(fp_line
			(start 0.508 -0.9398)
			(end -0.508 -0.9398)
			(stroke
				(width 0.1524)
				(type default)
			)
			(layer "F.SilkS")
		)
		(fp_line
			(start -0.508 -0.9398)
			(end -0.508 0.9398)
			(stroke
				(width 0.1524)
				(type default)
			)
			(layer "F.SilkS")
		)
		(fp_rect
			(start -0.508 0.9398)
			(end 0.508 -0.9398)
			(stroke
				(width 0)
				(type default)
			)
			(fill no)
			(layer "F.CrtYd")
		)
		(fp_rect
			(start -0.508 0.9398)
			(end 0.508 -0.9398)
			(stroke
				(width 0)
				(type default)
			)
			(fill no)
			(layer "F.Fab")
		)
		(pad "1" smd custom
			(at 0 -0.4445 180)
			(size 0.1397 0.1397)
			(layers "F.Cu" "F.Mask" "F.Paste")
			(net "P3V3_STBY_A")
			(options
				(clearance outline)
				(anchor circle)
			)
			(primitives
				(gr_poly
					(pts
						(arc
							(start -0.1778 -0.2794)
							(mid -0.249642 -0.249642)
							(end -0.2794 -0.1778)
						)
						(arc
							(start -0.2794 0.1778)
							(mid -0.249642 0.249642)
							(end -0.1778 0.2794)
						)
						(arc
							(start 0.1778 0.2794)
							(mid 0.249642 0.249642)
							(end 0.2794 0.1778)
						)
						(arc
							(start 0.2794 -0.1778)
							(mid 0.249642 -0.249642)
							(end 0.1778 -0.2794)
						)
					)
					(width 0)
					(fill yes)
				)
			)
		)
		(pad "2" smd custom
			(at 0 0.4445 180)
			(size 0.1397 0.1397)
			(layers "F.Cu" "F.Mask" "F.Paste")
			(net "IO_EXP2_HDD_FAULT_A1")
			(options
				(clearance outline)
				(anchor circle)
			)
			(primitives
				(gr_poly
					(pts
						(arc
							(start -0.1778 -0.2794)
							(mid -0.249642 -0.249642)
							(end -0.2794 -0.1778)
						)
						(arc
							(start -0.2794 0.1778)
							(mid -0.249642 0.249642)
							(end -0.1778 0.2794)
						)
						(arc
							(start 0.1778 0.2794)
							(mid 0.249642 0.249642)
							(end 0.2794 0.1778)
						)
						(arc
							(start 0.2794 -0.1778)
							(mid 0.249642 -0.249642)
							(end 0.1778 -0.2794)
						)
					)
					(width 0)
					(fill yes)
				)
			)
		)
	)
	(footprint ""
		(layer "F.Cu")
		(at 111.499396 -167.085518 90)
		(property "Reference" "R482"
			(at 0 0 90)
			(layer "F.SilkS")
			(hide yes)
			(effects
				(font
					(size 1.27 1.27)
				)
			)
		)
		(property "Value" "4K7R2J-2-GP"
			(at 0.064008 -3.993896 90)
			(unlocked yes)
			(layer "F.Fab")
			(hide yes)
			(effects
				(font
					(size 1.016 1.016)
					(thickness 0.1524)
				)
			)
		)
		(property "Device Type" "R402H16"
			(at 0.064008 -5.517896 90)
			(unlocked yes)
			(layer "F.Fab")
			(hide yes)
			(effects
				(font
					(size 1.016 1.016)
					(thickness 0.1524)
				)
			)
		)
		(duplicate_pad_numbers_are_jumpers no)
		(fp_line
			(start 0.508 -0.9398)
			(end -0.508 -0.9398)
			(stroke
				(width 0.1524)
				(type default)
			)
			(layer "F.SilkS")
		)
		(fp_line
			(start -0.508 -0.9398)
			(end -0.508 0.9398)
			(stroke
				(width 0.1524)
				(type default)
			)
			(layer "F.SilkS")
		)
		(fp_rect
			(start -0.508 0.9398)
			(end 0.508 -0.9398)
			(stroke
				(width 0)
				(type default)
			)
			(fill no)
			(layer "F.CrtYd")
		)
		(fp_rect
			(start -0.508 0.9398)
			(end 0.508 -0.9398)
			(stroke
				(width 0)
				(type default)
			)
			(fill no)
			(layer "F.Fab")
		)
		(pad "1" smd custom
			(at 0 -0.4445 90)
			(size 0.1397 0.1397)
			(layers "F.Cu" "F.Mask" "F.Paste")
			(net "P12V_A")
			(options
				(clearance outline)
				(anchor circle)
			)
			(primitives
				(gr_poly
					(pts
						(arc
							(start -0.1778 -0.2794)
							(mid -0.249642 -0.249642)
							(end -0.2794 -0.1778)
						)
						(arc
							(start -0.2794 0.1778)
							(mid -0.249642 0.249642)
							(end -0.1778 0.2794)
						)
						(arc
							(start 0.1778 0.2794)
							(mid 0.249642 0.249642)
							(end 0.2794 0.1778)
						)
						(arc
							(start 0.2794 -0.1778)
							(mid 0.249642 -0.249642)
							(end 0.1778 -0.2794)
						)
					)
					(width 0)
					(fill yes)
				)
			)
		)
		(pad "2" smd custom
			(at 0 0.4445 90)
			(size 0.1397 0.1397)
			(layers "F.Cu" "F.Mask" "F.Paste")
			(net "SW_HDD_P15")
			(options
				(clearance outline)
				(anchor circle)
			)
			(primitives
				(gr_poly
					(pts
						(arc
							(start -0.1778 -0.2794)
							(mid -0.249642 -0.249642)
							(end -0.2794 -0.1778)
						)
						(arc
							(start -0.2794 0.1778)
							(mid -0.249642 0.249642)
							(end -0.1778 0.2794)
						)
						(arc
							(start 0.1778 0.2794)
							(mid 0.249642 0.249642)
							(end 0.2794 0.1778)
						)
						(arc
							(start 0.2794 -0.1778)
							(mid 0.249642 -0.249642)
							(end 0.1778 -0.2794)
						)
					)
					(width 0)
					(fill yes)
				)
			)
		)
	)
)
